# S9S_MB_2U (Grand Teton) — schematic netlist excerpt (pin names and nets, part order shuffled) for the footprints in the layout excerpt that follows; sources: Cadence DE-HDL packaged netlist, KiCad conversion of 03242023_DA0F0TMBIJ0_F0T_Motherboard_J_brd_V01_OCP.brd

PC215  Q_CAP  3300PF 50V 10% X7R  pkg 0402  page 274 : A = SH_PVCCINFAON_CPU0_R ; B = VSENSE_PVCCINFAON_CPU0_DN
PJ53  Q_SHORT  EMPTY  pkg SM  page 266 : \1\ = VSENSE_PVCCFA_EHV_FIVRA_CPU0_DP ; \2\ = SH_PVCCFA_EHV_FIVRA_CPU0
PC2230  Q_CAP  1UF 25V 10% X6S  pkg C0402  page 242 : A = P12V_AUX ; B = GND

(kicad_pcb
	(version 20260206)
	(generator "pcbnew")
	(generator_version "10.0")
	(general
		(thickness 1.6)
		(legacy_teardrops no)
	)
	(paper "A4")
	(title_block
		(title "03242023_DA0F0TMBIJ0_F0T_Motherboard_J_brd_V01_OCP.brd")
		(comment 1 "Grand Teton / footprints 2071-2073 of 6105")
	)
	(layers
		(0 "F.Cu" signal "TOP")
		(4 "In1.Cu" signal "GND")
		(6 "In2.Cu" signal "IN1")
		(8 "In3.Cu" signal "GND1")
		(10 "In4.Cu" signal "IN2")
		(12 "In5.Cu" signal "GND2")
		(14 "In6.Cu" signal "IN3")
		(16 "In7.Cu" signal "GND3")
		(18 "In8.Cu" signal "VCC")
		(20 "In9.Cu" signal "VCC1")
		(22 "In10.Cu" signal "GND4")
		(24 "In11.Cu" signal "IN4")
		(26 "In12.Cu" signal "GND5")
		(28 "In13.Cu" signal "IN5")
		(30 "In14.Cu" signal "GND6")
		(32 "In15.Cu" signal "IN6")
		(34 "In16.Cu" signal "GND7")
		(2 "B.Cu" signal "BOTTOM")
		(9 "F.Adhes" user "F.Adhesive")
		(11 "B.Adhes" user "B.Adhesive")
		(13 "F.Paste" user "Package Geometry/Pastemask Top")
		(15 "B.Paste" user "Package Geometry/Pastemask Bottom")
		(5 "F.SilkS" user "Ref Des/Silkscreen Top")
		(7 "B.SilkS" user "Ref Des/Silkscreen Bottom")
		(1 "F.Mask" user "Board Geometry/Soldermask Top")
		(3 "B.Mask" user "Board Geometry/Soldermask Bottom")
		(17 "Dwgs.User" user "User.Drawings")
		(19 "Cmts.User" user "User.Comments")
		(21 "Eco1.User" user "User.Eco1")
		(23 "Eco2.User" user "User.Eco2")
		(25 "Edge.Cuts" user "Board Geometry/Outline")
		(27 "Margin" user)
		(31 "F.CrtYd" user "Package Geometry/Place Bound Top")
		(29 "B.CrtYd" user "Package Geometry/Place Bound Bottom")
		(35 "F.Fab" user "Ref Des/Assembly Top")
		(33 "B.Fab" user "Ref Des/Assembly Bottom")
	)
	(footprint ""
		(layer "F.Cu")
		(at 187.28436 -29.77769 -90)
		(property "Reference" "PC2230"
			(at 0 0 270)
			(layer "F.SilkS")
			(hide yes)
			(effects
				(font
					(size 1.27 1.27)
				)
			)
		)
		(property "Value" ""
			(at 0 0 270)
			(layer "F.Fab")
			(effects
				(font
					(size 1.27 1.27)
				)
			)
		)
		(duplicate_pad_numbers_are_jumpers no)
		(fp_line
			(start -0.7874 0.4064)
			(end -0.7874 -0.4064)
			(stroke
				(width 0.1524)
				(type default)
			)
			(layer "F.SilkS")
		)
		(fp_line
			(start 0.7874 0.4064)
			(end -0.7874 0.4064)
			(stroke
				(width 0.1524)
				(type default)
			)
			(layer "F.SilkS")
		)
		(fp_line
			(start -0.7874 -0.4064)
			(end 0.7874 -0.4064)
			(stroke
				(width 0.1524)
				(type default)
			)
			(layer "F.SilkS")
		)
		(fp_line
			(start 0.7874 -0.4064)
			(end 0.7874 0.4064)
			(stroke
				(width 0.1524)
				(type default)
			)
			(layer "F.SilkS")
		)
		(fp_line
			(start -0.67945 0.3048)
			(end -0.67945 -0.305054)
			(stroke
				(width 0.1)
				(type default)
			)
			(layer "F.Fab")
		)
		(fp_line
			(start -0.12065 0.3048)
			(end -0.67945 0.3048)
			(stroke
				(width 0.1)
				(type default)
			)
			(layer "F.Fab")
		)
		(fp_line
			(start 0.120396 0.3048)
			(end 0.120396 0.2794)
			(stroke
				(width 0.1)
				(type default)
			)
			(layer "F.Fab")
		)
		(fp_line
			(start 0.67945 0.3048)
			(end 0.120396 0.3048)
			(stroke
				(width 0.1)
				(type default)
			)
			(layer "F.Fab")
		)
		(fp_line
			(start -0.12065 0.2794)
			(end -0.12065 0.3048)
			(stroke
				(width 0.1)
				(type default)
			)
			(layer "F.Fab")
		)
		(fp_line
			(start 0.120396 0.2794)
			(end -0.12065 0.2794)
			(stroke
				(width 0.1)
				(type default)
			)
			(layer "F.Fab")
		)
		(fp_line
			(start -0.12065 -0.2794)
			(end 0.12065 -0.2794)
			(stroke
				(width 0.1)
				(type default)
			)
			(layer "F.Fab")
		)
		(fp_line
			(start 0.12065 -0.2794)
			(end 0.12065 -0.3048)
			(stroke
				(width 0.1)
				(type default)
			)
			(layer "F.Fab")
		)
		(fp_line
			(start 0.12065 -0.3048)
			(end 0.67945 -0.3048)
			(stroke
				(width 0.1)
				(type default)
			)
			(layer "F.Fab")
		)
		(fp_line
			(start 0.67945 -0.3048)
			(end 0.67945 0.3048)
			(stroke
				(width 0.1)
				(type default)
			)
			(layer "F.Fab")
		)
		(fp_line
			(start -0.67945 -0.305054)
			(end -0.12065 -0.305054)
			(stroke
				(width 0.1)
				(type default)
			)
			(layer "F.Fab")
		)
		(fp_line
			(start -0.12065 -0.305054)
			(end -0.12065 -0.2794)
			(stroke
				(width 0.1)
				(type default)
			)
			(layer "F.Fab")
		)
		(pad "1" smd circle
			(at -0.40005 0 270)
			(size 0 0)
			(layers "F.Cu" "F.Mask" "F.Paste")
			(net "P12V_AUX")
		)
		(pad "2" smd circle
			(at 0.40005 0 270)
			(size 0 0)
			(layers "F.Cu" "F.Mask" "F.Paste")
			(net "GND")
		)
	)
	(footprint ""
		(layer "F.Cu")
		(at 428.007526 -140.269214 180)
		(property "Reference" "PC215"
			(at 0 0 180)
			(layer "F.SilkS")
			(hide yes)
			(effects
				(font
					(size 1.27 1.27)
				)
			)
		)
		(property "Value" ""
			(at 0 0 180)
			(layer "F.Fab")
			(effects
				(font
					(size 1.27 1.27)
				)
			)
		)
		(duplicate_pad_numbers_are_jumpers no)
		(fp_line
			(start 0.7874 0.4064)
			(end -0.7874 0.4064)
			(stroke
				(width 0.1524)
				(type default)
			)
			(layer "F.SilkS")
		)
		(fp_line
			(start 0.7874 -0.4064)
			(end 0.7874 0.4064)
			(stroke
				(width 0.1524)
				(type default)
			)
			(layer "F.SilkS")
		)
		(fp_line
			(start -0.7874 0.4064)
			(end -0.7874 -0.4064)
			(stroke
				(width 0.1524)
				(type default)
			)
			(layer "F.SilkS")
		)
		(fp_line
			(start -0.7874 -0.4064)
			(end 0.7874 -0.4064)
			(stroke
				(width 0.1524)
				(type default)
			)
			(layer "F.SilkS")
		)
		(fp_line
			(start 0.67945 0.3048)
			(end 0.120396 0.3048)
			(stroke
				(width 0.1)
				(type default)
			)
			(layer "F.Fab")
		)
		(fp_line
			(start 0.67945 -0.3048)
			(end 0.67945 0.3048)
			(stroke
				(width 0.1)
				(type default)
			)
			(layer "F.Fab")
		)
		(fp_line
			(start 0.12065 -0.2794)
			(end 0.12065 -0.3048)
			(stroke
				(width 0.1)
				(type default)
			)
			(layer "F.Fab")
		)
		(fp_line
			(start 0.12065 -0.3048)
			(end 0.67945 -0.3048)
			(stroke
				(width 0.1)
				(type default)
			)
			(layer "F.Fab")
		)
		(fp_line
			(start 0.120396 0.3048)
			(end 0.120396 0.2794)
			(stroke
				(width 0.1)
				(type default)
			)
			(layer "F.Fab")
		)
		(fp_line
			(start 0.120396 0.2794)
			(end -0.12065 0.2794)
			(stroke
				(width 0.1)
				(type default)
			)
			(layer "F.Fab")
		)
		(fp_line
			(start -0.12065 0.3048)
			(end -0.67945 0.3048)
			(stroke
				(width 0.1)
				(type default)
			)
			(layer "F.Fab")
		)
		(fp_line
			(start -0.12065 0.2794)
			(end -0.12065 0.3048)
			(stroke
				(width 0.1)
				(type default)
			)
			(layer "F.Fab")
		)
		(fp_line
			(start -0.12065 -0.2794)
			(end 0.12065 -0.2794)
			(stroke
				(width 0.1)
				(type default)
			)
			(layer "F.Fab")
		)
		(fp_line
			(start -0.12065 -0.305054)
			(end -0.12065 -0.2794)
			(stroke
				(width 0.1)
				(type default)
			)
			(layer "F.Fab")
		)
		(fp_line
			(start -0.67945 0.3048)
			(end -0.67945 -0.305054)
			(stroke
				(width 0.1)
				(type default)
			)
			(layer "F.Fab")
		)
		(fp_line
			(start -0.67945 -0.305054)
			(end -0.12065 -0.305054)
			(stroke
				(width 0.1)
				(type default)
			)
			(layer "F.Fab")
		)
		(pad "1" smd circle
			(at -0.40005 0 180)
			(size 0 0)
			(layers "F.Cu" "F.Mask" "F.Paste")
			(net "SH_PVCCINFAON_CPU0_R")
		)
		(pad "2" smd circle
			(at 0.40005 0 180)
			(size 0 0)
			(layers "F.Cu" "F.Mask" "F.Paste")
			(net "VSENSE_PVCCINFAON_CPU0_DN")
		)
	)
	(footprint ""
		(layer "F.Cu")
		(at 363.62005 -355.985826 90)
		(property "Reference" "PJ53"
			(at -0.293878 1.27762 90)
			(unlocked yes)
			(layer "F.SilkS")
			(effects
				(font
					(size 0.7874 0.5842)
					(thickness 0.1524)
				)
				(justify left)
			)
		)
		(property "Value" ""
			(at 0 0 90)
			(layer "F.Fab")
			(effects
				(font
					(size 1.27 1.27)
				)
			)
		)
		(duplicate_pad_numbers_are_jumpers no)
		(pad "1" smd circle
			(at -0.7493 0 180)
			(size 0 0)
			(layers "F.Cu" "F.Mask" "F.Paste")
			(net "VSENSE_PVCCFA_EHV_FIVRA_CPU0_DP")
		)
		(pad "2" smd rect
			(at 0.7493 0)
			(size 0.7112 0.8128)
			(layers "F.Cu" "F.Mask" "F.Paste")
			(net "SH_PVCCFA_EHV_FIVRA_CPU0")
		)
		(zone
			(layer "F.Cu")
			(hatch none 0.5)
			(connect_pads
				(clearance 0)
			)
			(min_thickness 0.25)
			(keepout
				(tracks allowed)
				(vias not_allowed)
				(pads allowed)
				(copperpour not_allowed)
				(footprints allowed)
			)
			(placement
				(enabled no)
				(sheetname "")
			)
			(fill
				(thermal_gap 0.5)
				(thermal_bridge_width 0.5)
				(island_removal_mode 0)
			)
			(polygon
				(pts
					(xy 363.21365 -354.804726) (xy 364.031276 -354.804726) (xy 364.031276 -357.192326) (xy 363.21365 -357.192326)
				)
			)
		)
	)
)
